(kicad_pcb
	(version 20260206)
	(generator "pcbnew")
	(generator_version "10.0")
	(general
		(thickness 1.6)
		(legacy_teardrops no)
	)
	(paper "A4")
	(title_block
		(title "01162023_DA0F0TEBIF0_F0T_Expander_BD_F_brd_V02_OCP.brd")
		(comment 1 "Grand Teton / footprints 7954-7962 of 9728")
	)
	(layers
		(0 "F.Cu" signal "TOP")
		(4 "In1.Cu" signal "GND")
		(6 "In2.Cu" signal "VCC")
		(8 "In3.Cu" signal "VCC1")
		(10 "In4.Cu" signal "GND1")
		(12 "In5.Cu" signal "IN1")
		(14 "In6.Cu" signal "GND2")
		(16 "In7.Cu" signal "IN2")
		(18 "In8.Cu" signal "GND3")
		(20 "In9.Cu" signal "IN3")
		(22 "In10.Cu" signal "GND4")
		(24 "In11.Cu" signal "IN4")
		(26 "In12.Cu" signal "GND5")
		(28 "In13.Cu" signal "IN5")
		(30 "In14.Cu" signal "GND6")
		(32 "In15.Cu" signal "IN6")
		(34 "In16.Cu" signal "GND7")
		(2 "B.Cu" signal "BOTTOM")
		(9 "F.Adhes" user "F.Adhesive")
		(11 "B.Adhes" user "B.Adhesive")
		(13 "F.Paste" user "Package Geometry/Pastemask Top")
		(15 "B.Paste" user "Package Geometry/Pastemask Bottom")
		(5 "F.SilkS" user "Ref Des/Silkscreen Top")
		(7 "B.SilkS" user "Ref Des/Silkscreen Bottom")
		(1 "F.Mask" user "Board Geometry/Soldermask Top")
		(3 "B.Mask" user "Board Geometry/Soldermask Bottom")
		(17 "Dwgs.User" user "User.Drawings")
		(19 "Cmts.User" user "User.Comments")
		(21 "Eco1.User" user "User.Eco1")
		(23 "Eco2.User" user "User.Eco2")
		(25 "Edge.Cuts" user "Board Geometry/Outline")
		(27 "Margin" user)
		(31 "F.CrtYd" user "Package Geometry/Place Bound Top")
		(29 "B.CrtYd" user "Package Geometry/Place Bound Bottom")
		(35 "F.Fab" user "Ref Des/Assembly Top")
		(33 "B.Fab" user "Ref Des/Assembly Bottom")
	)
	(footprint ""
		(layer "B.Cu")
		(at 173.375066 -297.79976 90)
		(property "Reference" "C1407"
			(at 0 0 90)
			(layer "B.SilkS")
			(hide yes)
			(effects
				(font
					(size 1.27 1.27)
				)
				(justify mirror)
			)
		)
		(property "Value" ""
			(at 0 0 90)
			(layer "B.Fab")
			(effects
				(font
					(size 1.27 1.27)
				)
				(justify mirror)
			)
		)
		(duplicate_pad_numbers_are_jumpers no)
		(fp_line
			(start 0.299974 -0.150114)
			(end -0.299974 -0.150114)
			(stroke
				(width 0.1)
				(type default)
			)
			(layer "B.Fab")
		)
		(fp_line
			(start -0.299974 -0.150114)
			(end -0.299974 0.150114)
			(stroke
				(width 0.1)
				(type default)
			)
			(layer "B.Fab")
		)
		(fp_line
			(start 0.299974 0.150114)
			(end 0.299974 -0.150114)
			(stroke
				(width 0.1)
				(type default)
			)
			(layer "B.Fab")
		)
		(fp_line
			(start -0.299974 0.150114)
			(end 0.299974 0.150114)
			(stroke
				(width 0.1)
				(type default)
			)
			(layer "B.Fab")
		)
		(pad "1" smd rect
			(at 0.2667 0 270)
			(size 0.3048 0.381)
			(layers "B.Cu" "B.Mask" "B.Paste")
			(net "P0V8_PEX1")
		)
		(pad "2" smd rect
			(at -0.2667 0 270)
			(size 0.3048 0.381)
			(layers "B.Cu" "B.Mask" "B.Paste")
			(net "GND")
		)
	)
	(footprint ""
		(layer "B.Cu")
		(at 171.949872 -290.199826 90)
		(property "Reference" "C1452"
			(at 0 0 90)
			(layer "B.SilkS")
			(hide yes)
			(effects
				(font
					(size 1.27 1.27)
				)
				(justify mirror)
			)
		)
		(property "Value" ""
			(at 0 0 90)
			(layer "B.Fab")
			(effects
				(font
					(size 1.27 1.27)
				)
				(justify mirror)
			)
		)
		(duplicate_pad_numbers_are_jumpers no)
		(fp_line
			(start 0.299974 -0.150114)
			(end -0.299974 -0.150114)
			(stroke
				(width 0.1)
				(type default)
			)
			(layer "B.Fab")
		)
		(fp_line
			(start -0.299974 -0.150114)
			(end -0.299974 0.150114)
			(stroke
				(width 0.1)
				(type default)
			)
			(layer "B.Fab")
		)
		(fp_line
			(start 0.299974 0.150114)
			(end 0.299974 -0.150114)
			(stroke
				(width 0.1)
				(type default)
			)
			(layer "B.Fab")
		)
		(fp_line
			(start -0.299974 0.150114)
			(end 0.299974 0.150114)
			(stroke
				(width 0.1)
				(type default)
			)
			(layer "B.Fab")
		)
		(pad "1" smd rect
			(at 0.2667 0 270)
			(size 0.3048 0.381)
			(layers "B.Cu" "B.Mask" "B.Paste")
			(net "P0V8_SERDES_VDDA_PEX1")
		)
		(pad "2" smd rect
			(at -0.2667 0 270)
			(size 0.3048 0.381)
			(layers "B.Cu" "B.Mask" "B.Paste")
			(net "GND")
		)
	)
	(footprint ""
		(layer "B.Cu")
		(at 4.893818 -290.24707)
		(property "Reference" "PC987"
			(at 0 0 0)
			(layer "B.SilkS")
			(hide yes)
			(effects
				(font
					(size 1.27 1.27)
				)
				(justify mirror)
			)
		)
		(property "Value" ""
			(at 0 0 0)
			(layer "B.Fab")
			(effects
				(font
					(size 1.27 1.27)
				)
				(justify mirror)
			)
		)
		(duplicate_pad_numbers_are_jumpers no)
		(fp_line
			(start -1.524 -0.762)
			(end -1.524 0.762)
			(stroke
				(width 0.1524)
				(type default)
			)
			(layer "B.SilkS")
		)
		(fp_line
			(start -1.524 0.762)
			(end 1.524 0.762)
			(stroke
				(width 0.1524)
				(type default)
			)
			(layer "B.SilkS")
		)
		(fp_line
			(start 1.524 -0.762)
			(end -1.524 -0.762)
			(stroke
				(width 0.1524)
				(type default)
			)
			(layer "B.SilkS")
		)
		(fp_line
			(start 1.524 0.762)
			(end 1.524 -0.762)
			(stroke
				(width 0.1524)
				(type default)
			)
			(layer "B.SilkS")
		)
		(fp_line
			(start -1.1049 -0.724916)
			(end 1.1049 -0.724916)
			(stroke
				(width 0.1)
				(type default)
			)
			(layer "B.Fab")
		)
		(fp_line
			(start -1.1049 0.724916)
			(end -1.1049 -0.724916)
			(stroke
				(width 0.1)
				(type default)
			)
			(layer "B.Fab")
		)
		(fp_line
			(start 1.1049 -0.724916)
			(end 1.1049 0.724916)
			(stroke
				(width 0.1)
				(type default)
			)
			(layer "B.Fab")
		)
		(fp_line
			(start 1.1049 0.724916)
			(end -1.1049 0.724916)
			(stroke
				(width 0.1)
				(type default)
			)
			(layer "B.Fab")
		)
		(pad "1" smd rect
			(at 0.889 0)
			(size 1.016 1.27)
			(layers "B.Cu" "B.Mask" "B.Paste")
			(net "P1V25_PEX0_R")
		)
		(pad "2" smd rect
			(at -0.889 0)
			(size 1.016 1.27)
			(layers "B.Cu" "B.Mask" "B.Paste")
			(net "GND")
		)
	)
	(footprint ""
		(layer "B.Cu")
		(at 350.012 -207.772 -90)
		(property "Reference" "R5503"
			(at 0 0 90)
			(layer "B.SilkS")
			(hide yes)
			(effects
				(font
					(size 1.27 1.27)
				)
				(justify mirror)
			)
		)
		(property "Value" ""
			(at 0 0 90)
			(layer "B.Fab")
			(effects
				(font
					(size 1.27 1.27)
				)
				(justify mirror)
			)
		)
		(duplicate_pad_numbers_are_jumpers no)
		(fp_line
			(start -0.7874 0.4064)
			(end 0.7874 0.4064)
			(stroke
				(width 0.1524)
				(type default)
			)
			(layer "B.SilkS")
		)
		(fp_line
			(start 0.7874 0.4064)
			(end 0.7874 -0.4064)
			(stroke
				(width 0.1524)
				(type default)
			)
			(layer "B.SilkS")
		)
		(fp_line
			(start -0.7874 -0.4064)
			(end -0.7874 0.4064)
			(stroke
				(width 0.1524)
				(type default)
			)
			(layer "B.SilkS")
		)
		(fp_line
			(start 0.7874 -0.4064)
			(end -0.7874 -0.4064)
			(stroke
				(width 0.1524)
				(type default)
			)
			(layer "B.SilkS")
		)
		(fp_line
			(start -0.67945 0.3048)
			(end -0.120396 0.3048)
			(stroke
				(width 0.1)
				(type default)
			)
			(layer "B.Fab")
		)
		(fp_line
			(start -0.120396 0.3048)
			(end -0.120396 0.2794)
			(stroke
				(width 0.1)
				(type default)
			)
			(layer "B.Fab")
		)
		(fp_line
			(start 0.12065 0.3048)
			(end 0.67945 0.3048)
			(stroke
				(width 0.1)
				(type default)
			)
			(layer "B.Fab")
		)
		(fp_line
			(start 0.67945 0.3048)
			(end 0.67945 -0.305054)
			(stroke
				(width 0.1)
				(type default)
			)
			(layer "B.Fab")
		)
		(fp_line
			(start -0.120396 0.2794)
			(end 0.12065 0.2794)
			(stroke
				(width 0.1)
				(type default)
			)
			(layer "B.Fab")
		)
		(fp_line
			(start 0.12065 0.2794)
			(end 0.12065 0.3048)
			(stroke
				(width 0.1)
				(type default)
			)
			(layer "B.Fab")
		)
		(fp_line
			(start -0.12065 -0.2794)
			(end -0.12065 -0.3048)
			(stroke
				(width 0.1)
				(type default)
			)
			(layer "B.Fab")
		)
		(fp_line
			(start 0.12065 -0.2794)
			(end -0.12065 -0.2794)
			(stroke
				(width 0.1)
				(type default)
			)
			(layer "B.Fab")
		)
		(fp_line
			(start -0.67945 -0.3048)
			(end -0.67945 0.3048)
			(stroke
				(width 0.1)
				(type default)
			)
			(layer "B.Fab")
		)
		(fp_line
			(start -0.12065 -0.3048)
			(end -0.67945 -0.3048)
			(stroke
				(width 0.1)
				(type default)
			)
			(layer "B.Fab")
		)
		(fp_line
			(start 0.12065 -0.305054)
			(end 0.12065 -0.2794)
			(stroke
				(width 0.1)
				(type default)
			)
			(layer "B.Fab")
		)
		(fp_line
			(start 0.67945 -0.305054)
			(end 0.12065 -0.305054)
			(stroke
				(width 0.1)
				(type default)
			)
			(layer "B.Fab")
		)
		(pad "1" smd circle
			(at 0.40005 0 90)
			(size 0 0)
			(layers "B.Cu" "B.Mask" "B.Paste")
			(net "P3V3_AUX")
		)
		(pad "2" smd circle
			(at -0.40005 0 90)
			(size 0 0)
			(layers "B.Cu" "B.Mask" "B.Paste")
			(net "RST_FPGA_BIC_N")
		)
	)
	(footprint ""
		(layer "B.Cu")
		(at 281.755342 -155.0416)
		(property "Reference" "R231"
			(at 0 0 0)
			(layer "B.SilkS")
			(hide yes)
			(effects
				(font
					(size 1.27 1.27)
				)
				(justify mirror)
			)
		)
		(property "Value" ""
			(at 0 0 0)
			(layer "B.Fab")
			(effects
				(font
					(size 1.27 1.27)
				)
				(justify mirror)
			)
		)
		(duplicate_pad_numbers_are_jumpers no)
		(fp_line
			(start -0.7874 -0.4064)
			(end -0.7874 0.4064)
			(stroke
				(width 0.1524)
				(type default)
			)
			(layer "B.SilkS")
		)
		(fp_line
			(start -0.7874 0.4064)
			(end 0.7874 0.4064)
			(stroke
				(width 0.1524)
				(type default)
			)
			(layer "B.SilkS")
		)
		(fp_line
			(start 0.7874 -0.4064)
			(end -0.7874 -0.4064)
			(stroke
				(width 0.1524)
				(type default)
			)
			(layer "B.SilkS")
		)
		(fp_line
			(start 0.7874 0.4064)
			(end 0.7874 -0.4064)
			(stroke
				(width 0.1524)
				(type default)
			)
			(layer "B.SilkS")
		)
		(fp_line
			(start -0.67945 -0.3048)
			(end -0.67945 0.3048)
			(stroke
				(width 0.1)
				(type default)
			)
			(layer "B.Fab")
		)
		(fp_line
			(start -0.67945 0.3048)
			(end -0.120396 0.3048)
			(stroke
				(width 0.1)
				(type default)
			)
			(layer "B.Fab")
		)
		(fp_line
			(start -0.12065 -0.3048)
			(end -0.67945 -0.3048)
			(stroke
				(width 0.1)
				(type default)
			)
			(layer "B.Fab")
		)
		(fp_line
			(start -0.12065 -0.2794)
			(end -0.12065 -0.3048)
			(stroke
				(width 0.1)
				(type default)
			)
			(layer "B.Fab")
		)
		(fp_line
			(start -0.120396 0.2794)
			(end 0.12065 0.2794)
			(stroke
				(width 0.1)
				(type default)
			)
			(layer "B.Fab")
		)
		(fp_line
			(start -0.120396 0.3048)
			(end -0.120396 0.2794)
			(stroke
				(width 0.1)
				(type default)
			)
			(layer "B.Fab")
		)
		(fp_line
			(start 0.12065 -0.305054)
			(end 0.12065 -0.2794)
			(stroke
				(width 0.1)
				(type default)
			)
			(layer "B.Fab")
		)
		(fp_line
			(start 0.12065 -0.2794)
			(end -0.12065 -0.2794)
			(stroke
				(width 0.1)
				(type default)
			)
			(layer "B.Fab")
		)
		(fp_line
			(start 0.12065 0.2794)
			(end 0.12065 0.3048)
			(stroke
				(width 0.1)
				(type default)
			)
			(layer "B.Fab")
		)
		(fp_line
			(start 0.12065 0.3048)
			(end 0.67945 0.3048)
			(stroke
				(width 0.1)
				(type default)
			)
			(layer "B.Fab")
		)
		(fp_line
			(start 0.67945 -0.305054)
			(end 0.12065 -0.305054)
			(stroke
				(width 0.1)
				(type default)
			)
			(layer "B.Fab")
		)
		(fp_line
			(start 0.67945 0.3048)
			(end 0.67945 -0.305054)
			(stroke
				(width 0.1)
				(type default)
			)
			(layer "B.Fab")
		)
		(pad "1" smd circle
			(at 0.40005 0 180)
			(size 0 0)
			(layers "B.Cu" "B.Mask" "B.Paste")
			(net "NIC4_SLOT_ID1")
		)
		(pad "2" smd circle
			(at -0.40005 0 180)
			(size 0 0)
			(layers "B.Cu" "B.Mask" "B.Paste")
			(net "P3V3_NIC4")
		)
	)
	(footprint ""
		(layer "B.Cu")
		(at 301.536354 -234.958636 -90)
		(property "Reference" "R1863"
			(at 0 0 90)
			(layer "B.SilkS")
			(hide yes)
			(effects
				(font
					(size 1.27 1.27)
				)
				(justify mirror)
			)
		)
		(property "Value" ""
			(at 0 0 90)
			(layer "B.Fab")
			(effects
				(font
					(size 1.27 1.27)
				)
				(justify mirror)
			)
		)
		(duplicate_pad_numbers_are_jumpers no)
		(fp_line
			(start -0.7874 0.4064)
			(end 0.7874 0.4064)
			(stroke
				(width 0.1524)
				(type default)
			)
			(layer "B.SilkS")
		)
		(fp_line
			(start 0.7874 0.4064)
			(end 0.7874 -0.4064)
			(stroke
				(width 0.1524)
				(type default)
			)
			(layer "B.SilkS")
		)
		(fp_line
			(start -0.7874 -0.4064)
			(end -0.7874 0.4064)
			(stroke
				(width 0.1524)
				(type default)
			)
			(layer "B.SilkS")
		)
		(fp_line
			(start 0.7874 -0.4064)
			(end -0.7874 -0.4064)
			(stroke
				(width 0.1524)
				(type default)
			)
			(layer "B.SilkS")
		)
		(fp_line
			(start -0.67945 0.3048)
			(end -0.120396 0.3048)
			(stroke
				(width 0.1)
				(type default)
			)
			(layer "B.Fab")
		)
		(fp_line
			(start -0.120396 0.3048)
			(end -0.120396 0.2794)
			(stroke
				(width 0.1)
				(type default)
			)
			(layer "B.Fab")
		)
		(fp_line
			(start 0.12065 0.3048)
			(end 0.67945 0.3048)
			(stroke
				(width 0.1)
				(type default)
			)
			(layer "B.Fab")
		)
		(fp_line
			(start 0.67945 0.3048)
			(end 0.67945 -0.305054)
			(stroke
				(width 0.1)
				(type default)
			)
			(layer "B.Fab")
		)
		(fp_line
			(start -0.120396 0.2794)
			(end 0.12065 0.2794)
			(stroke
				(width 0.1)
				(type default)
			)
			(layer "B.Fab")
		)
		(fp_line
			(start 0.12065 0.2794)
			(end 0.12065 0.3048)
			(stroke
				(width 0.1)
				(type default)
			)
			(layer "B.Fab")
		)
		(fp_line
			(start -0.12065 -0.2794)
			(end -0.12065 -0.3048)
			(stroke
				(width 0.1)
				(type default)
			)
			(layer "B.Fab")
		)
		(fp_line
			(start 0.12065 -0.2794)
			(end -0.12065 -0.2794)
			(stroke
				(width 0.1)
				(type default)
			)
			(layer "B.Fab")
		)
		(fp_line
			(start -0.67945 -0.3048)
			(end -0.67945 0.3048)
			(stroke
				(width 0.1)
				(type default)
			)
			(layer "B.Fab")
		)
		(fp_line
			(start -0.12065 -0.3048)
			(end -0.67945 -0.3048)
			(stroke
				(width 0.1)
				(type default)
			)
			(layer "B.Fab")
		)
		(fp_line
			(start 0.12065 -0.305054)
			(end 0.12065 -0.2794)
			(stroke
				(width 0.1)
				(type default)
			)
			(layer "B.Fab")
		)
		(fp_line
			(start 0.67945 -0.305054)
			(end 0.12065 -0.305054)
			(stroke
				(width 0.1)
				(type default)
			)
			(layer "B.Fab")
		)
		(pad "1" smd circle
			(at 0.40005 0 90)
			(size 0 0)
			(layers "B.Cu" "B.Mask" "B.Paste")
			(net "P3V3_AUX")
		)
		(pad "2" smd circle
			(at -0.40005 0 90)
			(size 0 0)
			(layers "B.Cu" "B.Mask" "B.Paste")
			(net "RST_GPU_PERST_2_BUF_N")
		)
	)
	(footprint ""
		(layer "B.Cu")
		(at 305.6001 -112.604296)
		(property "Reference" "C922"
			(at 0 0 0)
			(layer "B.SilkS")
			(hide yes)
			(effects
				(font
					(size 1.27 1.27)
				)
				(justify mirror)
			)
		)
		(property "Value" ""
			(at 0 0 0)
			(layer "B.Fab")
			(effects
				(font
					(size 1.27 1.27)
				)
				(justify mirror)
			)
		)
		(duplicate_pad_numbers_are_jumpers no)
		(fp_line
			(start -0.299974 -0.150114)
			(end -0.299974 0.150114)
			(stroke
				(width 0.1)
				(type default)
			)
			(layer "B.Fab")
		)
		(fp_line
			(start -0.299974 0.150114)
			(end 0.299974 0.150114)
			(stroke
				(width 0.1)
				(type default)
			)
			(layer "B.Fab")
		)
		(fp_line
			(start 0.299974 -0.150114)
			(end -0.299974 -0.150114)
			(stroke
				(width 0.1)
				(type default)
			)
			(layer "B.Fab")
		)
		(fp_line
			(start 0.299974 0.150114)
			(end 0.299974 -0.150114)
			(stroke
				(width 0.1)
				(type default)
			)
			(layer "B.Fab")
		)
		(pad "1" smd rect
			(at 0.2667 0 180)
			(size 0.3048 0.381)
			(layers "B.Cu" "B.Mask" "B.Paste")
			(net "P12V_NIC5")
		)
		(pad "2" smd rect
			(at -0.2667 0 180)
			(size 0.3048 0.381)
			(layers "B.Cu" "B.Mask" "B.Paste")
			(net "GND")
		)
	)
	(footprint ""
		(layer "B.Cu")
		(at 138.947906 -173.846744 -90)
		(property "Reference" "L12"
			(at 0 0 90)
			(layer "B.SilkS")
			(hide yes)
			(effects
				(font
					(size 1.27 1.27)
				)
				(justify mirror)
			)
		)
		(property "Value" ""
			(at 0 0 90)
			(layer "B.Fab")
			(effects
				(font
					(size 1.27 1.27)
				)
				(justify mirror)
			)
		)
		(duplicate_pad_numbers_are_jumpers no)
		(fp_line
			(start -1.27 0.5842)
			(end 1.27 0.5842)
			(stroke
				(width 0.1524)
				(type default)
			)
			(layer "B.SilkS")
		)
		(fp_line
			(start -1.27 0.5842)
			(end -1.27 -0.5842)
			(stroke
				(width 0.1524)
				(type default)
			)
			(layer "B.SilkS")
		)
		(fp_line
			(start 1.27 0.5842)
			(end 1.27 -0.5842)
			(stroke
				(width 0.1524)
				(type default)
			)
			(layer "B.SilkS")
		)
		(fp_line
			(start 1.27 -0.5588)
			(end 1.27 -0.5842)
			(stroke
				(width 0.1524)
				(type default)
			)
			(layer "B.SilkS")
		)
		(fp_line
			(start 1.27 -0.5842)
			(end -1.27 -0.5842)
			(stroke
				(width 0.1524)
				(type default)
			)
			(layer "B.SilkS")
		)
		(fp_line
			(start -0.9144 0.508)
			(end 0.9144 0.508)
			(stroke
				(width 0.1)
				(type default)
			)
			(layer "B.Fab")
		)
		(fp_line
			(start 0.9144 0.508)
			(end 0.9144 0.406654)
			(stroke
				(width 0.1)
				(type default)
			)
			(layer "B.Fab")
		)
		(fp_line
			(start 0.9144 0.406654)
			(end 1.194308 0.406654)
			(stroke
				(width 0.1)
				(type default)
			)
			(layer "B.Fab")
		)
		(fp_line
			(start 1.194308 0.406654)
			(end 1.194308 -0.406654)
			(stroke
				(width 0.1)
				(type default)
			)
			(layer "B.Fab")
		)
		(fp_line
			(start -1.1938 0.4064)
			(end -0.9144 0.4064)
			(stroke
				(width 0.1)
				(type default)
			)
			(layer "B.Fab")
		)
		(fp_line
			(start -0.9144 0.4064)
			(end -0.9144 0.508)
			(stroke
				(width 0.1)
				(type default)
			)
			(layer "B.Fab")
		)
		(fp_line
			(start -1.1938 -0.406654)
			(end -1.1938 0.4064)
			(stroke
				(width 0.1)
				(type default)
			)
			(layer "B.Fab")
		)
		(fp_line
			(start -0.9144 -0.406654)
			(end -1.1938 -0.406654)
			(stroke
				(width 0.1)
				(type default)
			)
			(layer "B.Fab")
		)
		(fp_line
			(start 0.9144 -0.406654)
			(end 0.9144 -0.508)
			(stroke
				(width 0.1)
				(type default)
			)
			(layer "B.Fab")
		)
		(fp_line
			(start 1.194308 -0.406654)
			(end 0.9144 -0.406654)
			(stroke
				(width 0.1)
				(type default)
			)
			(layer "B.Fab")
		)
		(fp_line
			(start -0.9144 -0.508)
			(end -0.9144 -0.406654)
			(stroke
				(width 0.1)
				(type default)
			)
			(layer "B.Fab")
		)
		(fp_line
			(start 0.9144 -0.508)
			(end -0.9144 -0.508)
			(stroke
				(width 0.1)
				(type default)
			)
			(layer "B.Fab")
		)
		(pad "1" smd rect
			(at 0.7366 0 180)
			(size 0.7112 0.8128)
			(layers "B.Cu" "B.Mask" "B.Paste")
			(net "P3V3")
		)
		(pad "2" smd rect
			(at -0.7366 0 180)
			(size 0.7112 0.8128)
			(layers "B.Cu" "B.Mask" "B.Paste")
			(net "P3V3_DB2000QL_VDD")
		)
	)
	(footprint ""
		(layer "B.Cu")
		(at 118.456964 -316.868048)
		(property "Reference" "C4252"
			(at 0 0 0)
			(layer "B.SilkS")
			(hide yes)
			(effects
				(font
					(size 1.27 1.27)
				)
				(justify mirror)
			)
		)
		(property "Value" ""
			(at 0 0 0)
			(layer "B.Fab")
			(effects
				(font
					(size 1.27 1.27)
				)
				(justify mirror)
			)
		)
		(duplicate_pad_numbers_are_jumpers no)
		(fp_line
			(start -0.299974 -0.150114)
			(end -0.299974 0.150114)
			(stroke
				(width 0.1)
				(type default)
			)
			(layer "B.Fab")
		)
		(fp_line
			(start -0.299974 0.150114)
			(end 0.299974 0.150114)
			(stroke
				(width 0.1)
				(type default)
			)
			(layer "B.Fab")
		)
		(fp_line
			(start 0.299974 -0.150114)
			(end -0.299974 -0.150114)
			(stroke
				(width 0.1)
				(type default)
			)
			(layer "B.Fab")
		)
		(fp_line
			(start 0.299974 0.150114)
			(end 0.299974 -0.150114)
			(stroke
				(width 0.1)
				(type default)
			)
			(layer "B.Fab")
		)
		(pad "1" smd rect
			(at 0.2667 0 180)
			(size 0.3048 0.381)
			(layers "B.Cu" "B.Mask" "B.Paste")
			(net "P0V8_SERDES_VDDA_PEX1")
		)
		(pad "2" smd rect
			(at -0.2667 0 180)
			(size 0.3048 0.381)
			(layers "B.Cu" "B.Mask" "B.Paste")
			(net "GND")
		)
	)
)
